# T6G (Grand Teton) — schematic netlist excerpt (pin names and nets, part order shuffled) for the footprints in the layout excerpt that follows; sources: Cadence DE-HDL packaged netlist, KiCad conversion of 04192023_DAF0TMB3IC0_F0TG_MB_C_brd_V02_OCP.brd

PC147_6  Q_CAP  22UF 16V 20% X6S  pkg C0805  page 220 : A = SW_P12V_AUX_PVDDCR_CPU1_P1_FLT ; B = GND
R3032  Q_RES  100K 1% EMPTY  pkg 0402LF  page 127 : A = FM_SMB_2_ALERT_GPU_N ; B = GND
R1157  Q_RES  33 5% EMPTY  pkg 0402LF  page 161 : A = SMB_APML_CPU1_R_SCL ; B = SMB_APML_CPU1_SCL

(kicad_pcb
	(version 20260206)
	(generator "pcbnew")
	(generator_version "10.0")
	(general
		(thickness 1.6)
		(legacy_teardrops no)
	)
	(paper "A4")
	(title_block
		(title "04192023_DAF0TMB3IC0_F0TG_MB_C_brd_V02_OCP.brd")
		(comment 1 "Grand Teton / footprints 5499-5501 of 8354")
	)
	(layers
		(0 "F.Cu" signal "TOP")
		(4 "In1.Cu" signal "GND")
		(6 "In2.Cu" signal "IN1")
		(8 "In3.Cu" signal "GND1")
		(10 "In4.Cu" signal "IN2")
		(12 "In5.Cu" signal "GND2")
		(14 "In6.Cu" signal "IN3")
		(16 "In7.Cu" signal "GND3")
		(18 "In8.Cu" signal "VCC")
		(20 "In9.Cu" signal "VCC1")
		(22 "In10.Cu" signal "GND4")
		(24 "In11.Cu" signal "IN4")
		(26 "In12.Cu" signal "GND5")
		(28 "In13.Cu" signal "IN5")
		(30 "In14.Cu" signal "GND6")
		(32 "In15.Cu" signal "IN6")
		(34 "In16.Cu" signal "GND7")
		(2 "B.Cu" signal "BOTTOM")
		(9 "F.Adhes" user "F.Adhesive")
		(11 "B.Adhes" user "B.Adhesive")
		(13 "F.Paste" user "Package Geometry/Pastemask Top")
		(15 "B.Paste" user "Package Geometry/Pastemask Bottom")
		(5 "F.SilkS" user "Ref Des/Silkscreen Top")
		(7 "B.SilkS" user "Ref Des/Silkscreen Bottom")
		(1 "F.Mask" user "Board Geometry/Soldermask Top")
		(3 "B.Mask" user "Board Geometry/Soldermask Bottom")
		(17 "Dwgs.User" user "User.Drawings")
		(19 "Cmts.User" user "User.Comments")
		(21 "Eco1.User" user "User.Eco1")
		(23 "Eco2.User" user "User.Eco2")
		(25 "Edge.Cuts" user "Board Geometry/Outline")
		(27 "Margin" user)
		(31 "F.CrtYd" user "Package Geometry/Place Bound Top")
		(29 "B.CrtYd" user "Package Geometry/Place Bound Bottom")
		(35 "F.Fab" user "Ref Des/Assembly Top")
		(33 "B.Fab" user "Ref Des/Assembly Bottom")
	)
	(footprint ""
		(layer "B.Cu")
		(at 105.537 -419.989)
		(property "Reference" "R3032"
			(at 0 0 0)
			(layer "B.SilkS")
			(hide yes)
			(effects
				(font
					(size 1.27 1.27)
				)
				(justify mirror)
			)
		)
		(property "Value" ""
			(at 0 0 0)
			(layer "B.Fab")
			(effects
				(font
					(size 1.27 1.27)
				)
				(justify mirror)
			)
		)
		(duplicate_pad_numbers_are_jumpers no)
		(fp_line
			(start -0.7874 -0.4064)
			(end -0.7874 0.4064)
			(stroke
				(width 0.1524)
				(type default)
			)
			(layer "B.SilkS")
		)
		(fp_line
			(start -0.7874 0.4064)
			(end 0.7874 0.4064)
			(stroke
				(width 0.1524)
				(type default)
			)
			(layer "B.SilkS")
		)
		(fp_line
			(start 0.7874 -0.4064)
			(end -0.7874 -0.4064)
			(stroke
				(width 0.1524)
				(type default)
			)
			(layer "B.SilkS")
		)
		(fp_line
			(start 0.7874 0.4064)
			(end 0.7874 -0.4064)
			(stroke
				(width 0.1524)
				(type default)
			)
			(layer "B.SilkS")
		)
		(fp_line
			(start -0.67945 -0.3048)
			(end -0.67945 0.3048)
			(stroke
				(width 0.1)
				(type default)
			)
			(layer "B.Fab")
		)
		(fp_line
			(start -0.67945 0.3048)
			(end -0.120396 0.3048)
			(stroke
				(width 0.1)
				(type default)
			)
			(layer "B.Fab")
		)
		(fp_line
			(start -0.12065 -0.3048)
			(end -0.67945 -0.3048)
			(stroke
				(width 0.1)
				(type default)
			)
			(layer "B.Fab")
		)
		(fp_line
			(start -0.12065 -0.2794)
			(end -0.12065 -0.3048)
			(stroke
				(width 0.1)
				(type default)
			)
			(layer "B.Fab")
		)
		(fp_line
			(start -0.120396 0.2794)
			(end 0.12065 0.2794)
			(stroke
				(width 0.1)
				(type default)
			)
			(layer "B.Fab")
		)
		(fp_line
			(start -0.120396 0.3048)
			(end -0.120396 0.2794)
			(stroke
				(width 0.1)
				(type default)
			)
			(layer "B.Fab")
		)
		(fp_line
			(start 0.12065 -0.305054)
			(end 0.12065 -0.2794)
			(stroke
				(width 0.1)
				(type default)
			)
			(layer "B.Fab")
		)
		(fp_line
			(start 0.12065 -0.2794)
			(end -0.12065 -0.2794)
			(stroke
				(width 0.1)
				(type default)
			)
			(layer "B.Fab")
		)
		(fp_line
			(start 0.12065 0.2794)
			(end 0.12065 0.3048)
			(stroke
				(width 0.1)
				(type default)
			)
			(layer "B.Fab")
		)
		(fp_line
			(start 0.12065 0.3048)
			(end 0.67945 0.3048)
			(stroke
				(width 0.1)
				(type default)
			)
			(layer "B.Fab")
		)
		(fp_line
			(start 0.67945 -0.305054)
			(end 0.12065 -0.305054)
			(stroke
				(width 0.1)
				(type default)
			)
			(layer "B.Fab")
		)
		(fp_line
			(start 0.67945 0.3048)
			(end 0.67945 -0.305054)
			(stroke
				(width 0.1)
				(type default)
			)
			(layer "B.Fab")
		)
		(pad "1" smd circle
			(at 0.40005 0 180)
			(size 0 0)
			(layers "B.Cu" "B.Mask" "B.Paste")
			(net "FM_SMB_2_ALERT_GPU_N")
		)
		(pad "2" smd circle
			(at -0.40005 0 180)
			(size 0 0)
			(layers "B.Cu" "B.Mask" "B.Paste")
			(net "GND")
		)
	)
	(footprint ""
		(layer "B.Cu")
		(at 104.850946 -343.878916 -90)
		(property "Reference" "PC147_6"
			(at 0 0 90)
			(layer "B.SilkS")
			(hide yes)
			(effects
				(font
					(size 1.27 1.27)
				)
				(justify mirror)
			)
		)
		(property "Value" ""
			(at 0 0 90)
			(layer "B.Fab")
			(effects
				(font
					(size 1.27 1.27)
				)
				(justify mirror)
			)
		)
		(duplicate_pad_numbers_are_jumpers no)
		(fp_line
			(start -1.524 0.762)
			(end 1.524 0.762)
			(stroke
				(width 0.1524)
				(type default)
			)
			(layer "B.SilkS")
		)
		(fp_line
			(start 1.524 0.762)
			(end 1.524 -0.762)
			(stroke
				(width 0.1524)
				(type default)
			)
			(layer "B.SilkS")
		)
		(fp_line
			(start -1.524 -0.762)
			(end -1.524 0.762)
			(stroke
				(width 0.1524)
				(type default)
			)
			(layer "B.SilkS")
		)
		(fp_line
			(start 1.524 -0.762)
			(end -1.524 -0.762)
			(stroke
				(width 0.1524)
				(type default)
			)
			(layer "B.SilkS")
		)
		(fp_line
			(start -1.1049 0.724916)
			(end -1.1049 -0.724916)
			(stroke
				(width 0.1)
				(type default)
			)
			(layer "B.Fab")
		)
		(fp_line
			(start 1.1049 0.724916)
			(end -1.1049 0.724916)
			(stroke
				(width 0.1)
				(type default)
			)
			(layer "B.Fab")
		)
		(fp_line
			(start -1.1049 -0.724916)
			(end 1.1049 -0.724916)
			(stroke
				(width 0.1)
				(type default)
			)
			(layer "B.Fab")
		)
		(fp_line
			(start 1.1049 -0.724916)
			(end 1.1049 0.724916)
			(stroke
				(width 0.1)
				(type default)
			)
			(layer "B.Fab")
		)
		(pad "1" smd rect
			(at 0.889 0 270)
			(size 1.016 1.27)
			(layers "B.Cu" "B.Mask" "B.Paste")
			(net "SW_P12V_AUX_PVDDCR_CPU1_P1_FLT")
		)
		(pad "2" smd rect
			(at -0.889 0 270)
			(size 1.016 1.27)
			(layers "B.Cu" "B.Mask" "B.Paste")
			(net "GND")
		)
	)
	(footprint ""
		(layer "B.Cu")
		(at 235.839 -240.411 -90)
		(property "Reference" "R1157"
			(at 0 0 90)
			(layer "B.SilkS")
			(hide yes)
			(effects
				(font
					(size 1.27 1.27)
				)
				(justify mirror)
			)
		)
		(property "Value" ""
			(at 0 0 90)
			(layer "B.Fab")
			(effects
				(font
					(size 1.27 1.27)
				)
				(justify mirror)
			)
		)
		(duplicate_pad_numbers_are_jumpers no)
		(fp_line
			(start -0.7874 0.4064)
			(end 0.7874 0.4064)
			(stroke
				(width 0.1524)
				(type default)
			)
			(layer "B.SilkS")
		)
		(fp_line
			(start 0.7874 0.4064)
			(end 0.7874 -0.4064)
			(stroke
				(width 0.1524)
				(type default)
			)
			(layer "B.SilkS")
		)
		(fp_line
			(start -0.7874 -0.4064)
			(end -0.7874 0.4064)
			(stroke
				(width 0.1524)
				(type default)
			)
			(layer "B.SilkS")
		)
		(fp_line
			(start 0.7874 -0.4064)
			(end -0.7874 -0.4064)
			(stroke
				(width 0.1524)
				(type default)
			)
			(layer "B.SilkS")
		)
		(fp_line
			(start -0.67945 0.3048)
			(end -0.120396 0.3048)
			(stroke
				(width 0.1)
				(type default)
			)
			(layer "B.Fab")
		)
		(fp_line
			(start -0.120396 0.3048)
			(end -0.120396 0.2794)
			(stroke
				(width 0.1)
				(type default)
			)
			(layer "B.Fab")
		)
		(fp_line
			(start 0.12065 0.3048)
			(end 0.67945 0.3048)
			(stroke
				(width 0.1)
				(type default)
			)
			(layer "B.Fab")
		)
		(fp_line
			(start 0.67945 0.3048)
			(end 0.67945 -0.305054)
			(stroke
				(width 0.1)
				(type default)
			)
			(layer "B.Fab")
		)
		(fp_line
			(start -0.120396 0.2794)
			(end 0.12065 0.2794)
			(stroke
				(width 0.1)
				(type default)
			)
			(layer "B.Fab")
		)
		(fp_line
			(start 0.12065 0.2794)
			(end 0.12065 0.3048)
			(stroke
				(width 0.1)
				(type default)
			)
			(layer "B.Fab")
		)
		(fp_line
			(start -0.12065 -0.2794)
			(end -0.12065 -0.3048)
			(stroke
				(width 0.1)
				(type default)
			)
			(layer "B.Fab")
		)
		(fp_line
			(start 0.12065 -0.2794)
			(end -0.12065 -0.2794)
			(stroke
				(width 0.1)
				(type default)
			)
			(layer "B.Fab")
		)
		(fp_line
			(start -0.67945 -0.3048)
			(end -0.67945 0.3048)
			(stroke
				(width 0.1)
				(type default)
			)
			(layer "B.Fab")
		)
		(fp_line
			(start -0.12065 -0.3048)
			(end -0.67945 -0.3048)
			(stroke
				(width 0.1)
				(type default)
			)
			(layer "B.Fab")
		)
		(fp_line
			(start 0.12065 -0.305054)
			(end 0.12065 -0.2794)
			(stroke
				(width 0.1)
				(type default)
			)
			(layer "B.Fab")
		)
		(fp_line
			(start 0.67945 -0.305054)
			(end 0.12065 -0.305054)
			(stroke
				(width 0.1)
				(type default)
			)
			(layer "B.Fab")
		)
		(pad "1" smd rect
			(at 0.40005 0 270)
			(size 0.4572 0.508)
			(layers "B.Cu" "B.Mask" "B.Paste")
			(net "SMB_APML_CPU1_R_SCL")
		)
		(pad "2" smd rect
			(at -0.40005 0 270)
			(size 0.4572 0.508)
			(layers "B.Cu" "B.Mask" "B.Paste")
			(net "SMB_APML_CPU1_SCL")
		)
	)
)
